(kicad_pcb
	(version 20260206)
	(generator "pcbnew")
	(generator_version "10.0")
	(general
		(thickness 1.6)
		(legacy_teardrops no)
	)
	(paper "A4")
	(title_block
		(title "01162023_DA0F0TEBIF0_F0T_Expander_BD_F_brd_V02_OCP.brd")
		(comment 1 "Grand Teton / footprints 6775-6781 of 9728")
	)
	(layers
		(0 "F.Cu" signal "TOP")
		(4 "In1.Cu" signal "GND")
		(6 "In2.Cu" signal "VCC")
		(8 "In3.Cu" signal "VCC1")
		(10 "In4.Cu" signal "GND1")
		(12 "In5.Cu" signal "IN1")
		(14 "In6.Cu" signal "GND2")
		(16 "In7.Cu" signal "IN2")
		(18 "In8.Cu" signal "GND3")
		(20 "In9.Cu" signal "IN3")
		(22 "In10.Cu" signal "GND4")
		(24 "In11.Cu" signal "IN4")
		(26 "In12.Cu" signal "GND5")
		(28 "In13.Cu" signal "IN5")
		(30 "In14.Cu" signal "GND6")
		(32 "In15.Cu" signal "IN6")
		(34 "In16.Cu" signal "GND7")
		(2 "B.Cu" signal "BOTTOM")
		(9 "F.Adhes" user "F.Adhesive")
		(11 "B.Adhes" user "B.Adhesive")
		(13 "F.Paste" user "Package Geometry/Pastemask Top")
		(15 "B.Paste" user "Package Geometry/Pastemask Bottom")
		(5 "F.SilkS" user "Ref Des/Silkscreen Top")
		(7 "B.SilkS" user "Ref Des/Silkscreen Bottom")
		(1 "F.Mask" user "Board Geometry/Soldermask Top")
		(3 "B.Mask" user "Board Geometry/Soldermask Bottom")
		(17 "Dwgs.User" user "User.Drawings")
		(19 "Cmts.User" user "User.Comments")
		(21 "Eco1.User" user "User.Eco1")
		(23 "Eco2.User" user "User.Eco2")
		(25 "Edge.Cuts" user "Board Geometry/Outline")
		(27 "Margin" user)
		(31 "F.CrtYd" user "Package Geometry/Place Bound Top")
		(29 "B.CrtYd" user "Package Geometry/Place Bound Bottom")
		(35 "F.Fab" user "Ref Des/Assembly Top")
		(33 "B.Fab" user "Ref Des/Assembly Bottom")
	)
	(footprint ""
		(layer "F.Cu")
		(at 262.07212 -32.848042 90)
		(property "Reference" "PC942"
			(at 0 0 90)
			(layer "F.SilkS")
			(hide yes)
			(effects
				(font
					(size 1.27 1.27)
				)
			)
		)
		(property "Value" ""
			(at 0 0 90)
			(layer "F.Fab")
			(effects
				(font
					(size 1.27 1.27)
				)
			)
		)
		(duplicate_pad_numbers_are_jumpers no)
		(fp_line
			(start 0.7874 -0.4064)
			(end 0.7874 0.4064)
			(stroke
				(width 0.1524)
				(type default)
			)
			(layer "F.SilkS")
		)
		(fp_line
			(start -0.7874 -0.4064)
			(end 0.7874 -0.4064)
			(stroke
				(width 0.1524)
				(type default)
			)
			(layer "F.SilkS")
		)
		(fp_line
			(start 0.7874 0.4064)
			(end -0.7874 0.4064)
			(stroke
				(width 0.1524)
				(type default)
			)
			(layer "F.SilkS")
		)
		(fp_line
			(start -0.7874 0.4064)
			(end -0.7874 -0.4064)
			(stroke
				(width 0.1524)
				(type default)
			)
			(layer "F.SilkS")
		)
		(fp_line
			(start -0.12065 -0.305054)
			(end -0.12065 -0.2794)
			(stroke
				(width 0.1)
				(type default)
			)
			(layer "F.Fab")
		)
		(fp_line
			(start -0.67945 -0.305054)
			(end -0.12065 -0.305054)
			(stroke
				(width 0.1)
				(type default)
			)
			(layer "F.Fab")
		)
		(fp_line
			(start 0.67945 -0.3048)
			(end 0.67945 0.3048)
			(stroke
				(width 0.1)
				(type default)
			)
			(layer "F.Fab")
		)
		(fp_line
			(start 0.12065 -0.3048)
			(end 0.67945 -0.3048)
			(stroke
				(width 0.1)
				(type default)
			)
			(layer "F.Fab")
		)
		(fp_line
			(start 0.12065 -0.2794)
			(end 0.12065 -0.3048)
			(stroke
				(width 0.1)
				(type default)
			)
			(layer "F.Fab")
		)
		(fp_line
			(start -0.12065 -0.2794)
			(end 0.12065 -0.2794)
			(stroke
				(width 0.1)
				(type default)
			)
			(layer "F.Fab")
		)
		(fp_line
			(start 0.120396 0.2794)
			(end -0.12065 0.2794)
			(stroke
				(width 0.1)
				(type default)
			)
			(layer "F.Fab")
		)
		(fp_line
			(start -0.12065 0.2794)
			(end -0.12065 0.3048)
			(stroke
				(width 0.1)
				(type default)
			)
			(layer "F.Fab")
		)
		(fp_line
			(start 0.67945 0.3048)
			(end 0.120396 0.3048)
			(stroke
				(width 0.1)
				(type default)
			)
			(layer "F.Fab")
		)
		(fp_line
			(start 0.120396 0.3048)
			(end 0.120396 0.2794)
			(stroke
				(width 0.1)
				(type default)
			)
			(layer "F.Fab")
		)
		(fp_line
			(start -0.12065 0.3048)
			(end -0.67945 0.3048)
			(stroke
				(width 0.1)
				(type default)
			)
			(layer "F.Fab")
		)
		(fp_line
			(start -0.67945 0.3048)
			(end -0.67945 -0.305054)
			(stroke
				(width 0.1)
				(type default)
			)
			(layer "F.Fab")
		)
		(pad "1" smd circle
			(at -0.40005 0 90)
			(size 0 0)
			(layers "F.Cu" "F.Mask" "F.Paste")
			(net "P3V3_SSD9_CO_GATE")
		)
		(pad "2" smd circle
			(at 0.40005 0 90)
			(size 0 0)
			(layers "F.Cu" "F.Mask" "F.Paste")
			(net "GND")
		)
	)
	(footprint ""
		(layer "F.Cu")
		(at 31.394146 -29.507688 -90)
		(property "Reference" "PC673"
			(at 0 0 270)
			(layer "F.SilkS")
			(hide yes)
			(effects
				(font
					(size 1.27 1.27)
				)
			)
		)
		(property "Value" ""
			(at 0 0 270)
			(layer "F.Fab")
			(effects
				(font
					(size 1.27 1.27)
				)
			)
		)
		(duplicate_pad_numbers_are_jumpers no)
		(fp_line
			(start -1.524 0.762)
			(end -1.524 -0.762)
			(stroke
				(width 0.1524)
				(type default)
			)
			(layer "F.SilkS")
		)
		(fp_line
			(start 1.524 0.762)
			(end -1.524 0.762)
			(stroke
				(width 0.1524)
				(type default)
			)
			(layer "F.SilkS")
		)
		(fp_line
			(start -1.524 -0.762)
			(end 1.524 -0.762)
			(stroke
				(width 0.1524)
				(type default)
			)
			(layer "F.SilkS")
		)
		(fp_line
			(start 1.524 -0.762)
			(end 1.524 0.762)
			(stroke
				(width 0.1524)
				(type default)
			)
			(layer "F.SilkS")
		)
		(fp_line
			(start -1.1049 0.724916)
			(end 1.1049 0.724916)
			(stroke
				(width 0.1)
				(type default)
			)
			(layer "F.Fab")
		)
		(fp_line
			(start 1.1049 0.724916)
			(end 1.1049 -0.724916)
			(stroke
				(width 0.1)
				(type default)
			)
			(layer "F.Fab")
		)
		(fp_line
			(start -1.1049 -0.724916)
			(end -1.1049 0.724916)
			(stroke
				(width 0.1)
				(type default)
			)
			(layer "F.Fab")
		)
		(fp_line
			(start 1.1049 -0.724916)
			(end -1.1049 -0.724916)
			(stroke
				(width 0.1)
				(type default)
			)
			(layer "F.Fab")
		)
		(pad "1" smd rect
			(at -0.889 0 90)
			(size 1.016 1.27)
			(layers "F.Cu" "F.Mask" "F.Paste")
			(net "P3V3_SSD1")
		)
		(pad "2" smd rect
			(at 0.889 0 90)
			(size 1.016 1.27)
			(layers "F.Cu" "F.Mask" "F.Paste")
			(net "GND")
		)
	)
	(footprint ""
		(layer "F.Cu")
		(at 205.105254 -298.87291 -90)
		(property "Reference" "R3926"
			(at 0 0 270)
			(layer "F.SilkS")
			(hide yes)
			(effects
				(font
					(size 1.27 1.27)
				)
			)
		)
		(property "Value" ""
			(at 0 0 270)
			(layer "F.Fab")
			(effects
				(font
					(size 1.27 1.27)
				)
			)
		)
		(duplicate_pad_numbers_are_jumpers no)
		(fp_line
			(start -0.7874 0.4064)
			(end -0.7874 -0.4064)
			(stroke
				(width 0.1524)
				(type default)
			)
			(layer "F.SilkS")
		)
		(fp_line
			(start 0.7874 0.4064)
			(end -0.7874 0.4064)
			(stroke
				(width 0.1524)
				(type default)
			)
			(layer "F.SilkS")
		)
		(fp_line
			(start -0.7874 -0.4064)
			(end 0.7874 -0.4064)
			(stroke
				(width 0.1524)
				(type default)
			)
			(layer "F.SilkS")
		)
		(fp_line
			(start 0.7874 -0.4064)
			(end 0.7874 0.4064)
			(stroke
				(width 0.1524)
				(type default)
			)
			(layer "F.SilkS")
		)
		(fp_line
			(start -0.67945 0.3048)
			(end -0.67945 -0.305054)
			(stroke
				(width 0.1)
				(type default)
			)
			(layer "F.Fab")
		)
		(fp_line
			(start -0.12065 0.3048)
			(end -0.67945 0.3048)
			(stroke
				(width 0.1)
				(type default)
			)
			(layer "F.Fab")
		)
		(fp_line
			(start 0.120396 0.3048)
			(end 0.120396 0.2794)
			(stroke
				(width 0.1)
				(type default)
			)
			(layer "F.Fab")
		)
		(fp_line
			(start 0.67945 0.3048)
			(end 0.120396 0.3048)
			(stroke
				(width 0.1)
				(type default)
			)
			(layer "F.Fab")
		)
		(fp_line
			(start -0.12065 0.2794)
			(end -0.12065 0.3048)
			(stroke
				(width 0.1)
				(type default)
			)
			(layer "F.Fab")
		)
		(fp_line
			(start 0.120396 0.2794)
			(end -0.12065 0.2794)
			(stroke
				(width 0.1)
				(type default)
			)
			(layer "F.Fab")
		)
		(fp_line
			(start -0.12065 -0.2794)
			(end 0.12065 -0.2794)
			(stroke
				(width 0.1)
				(type default)
			)
			(layer "F.Fab")
		)
		(fp_line
			(start 0.12065 -0.2794)
			(end 0.12065 -0.3048)
			(stroke
				(width 0.1)
				(type default)
			)
			(layer "F.Fab")
		)
		(fp_line
			(start 0.12065 -0.3048)
			(end 0.67945 -0.3048)
			(stroke
				(width 0.1)
				(type default)
			)
			(layer "F.Fab")
		)
		(fp_line
			(start 0.67945 -0.3048)
			(end 0.67945 0.3048)
			(stroke
				(width 0.1)
				(type default)
			)
			(layer "F.Fab")
		)
		(fp_line
			(start -0.67945 -0.305054)
			(end -0.12065 -0.305054)
			(stroke
				(width 0.1)
				(type default)
			)
			(layer "F.Fab")
		)
		(fp_line
			(start -0.12065 -0.305054)
			(end -0.12065 -0.2794)
			(stroke
				(width 0.1)
				(type default)
			)
			(layer "F.Fab")
		)
		(pad "1" smd circle
			(at -0.40005 0 270)
			(size 0 0)
			(layers "F.Cu" "F.Mask" "F.Paste")
			(net "I2C_PEX1_HOST_SDA")
		)
		(pad "2" smd circle
			(at 0.40005 0 270)
			(size 0 0)
			(layers "F.Cu" "F.Mask" "F.Paste")
			(net "I2C_PEX1_HOST_R_SDA")
		)
	)
	(footprint ""
		(layer "F.Cu")
		(at 339.344 -238.633 -90)
		(property "Reference" "R1794"
			(at 0 0 270)
			(layer "F.SilkS")
			(hide yes)
			(effects
				(font
					(size 1.27 1.27)
				)
			)
		)
		(property "Value" ""
			(at 0 0 270)
			(layer "F.Fab")
			(effects
				(font
					(size 1.27 1.27)
				)
			)
		)
		(duplicate_pad_numbers_are_jumpers no)
		(fp_line
			(start -0.7874 0.4064)
			(end -0.7874 -0.4064)
			(stroke
				(width 0.1524)
				(type default)
			)
			(layer "F.SilkS")
		)
		(fp_line
			(start 0.7874 0.4064)
			(end -0.7874 0.4064)
			(stroke
				(width 0.1524)
				(type default)
			)
			(layer "F.SilkS")
		)
		(fp_line
			(start -0.7874 -0.4064)
			(end 0.7874 -0.4064)
			(stroke
				(width 0.1524)
				(type default)
			)
			(layer "F.SilkS")
		)
		(fp_line
			(start 0.7874 -0.4064)
			(end 0.7874 0.4064)
			(stroke
				(width 0.1524)
				(type default)
			)
			(layer "F.SilkS")
		)
		(fp_line
			(start -0.67945 0.3048)
			(end -0.67945 -0.305054)
			(stroke
				(width 0.1)
				(type default)
			)
			(layer "F.Fab")
		)
		(fp_line
			(start -0.12065 0.3048)
			(end -0.67945 0.3048)
			(stroke
				(width 0.1)
				(type default)
			)
			(layer "F.Fab")
		)
		(fp_line
			(start 0.120396 0.3048)
			(end 0.120396 0.2794)
			(stroke
				(width 0.1)
				(type default)
			)
			(layer "F.Fab")
		)
		(fp_line
			(start 0.67945 0.3048)
			(end 0.120396 0.3048)
			(stroke
				(width 0.1)
				(type default)
			)
			(layer "F.Fab")
		)
		(fp_line
			(start -0.12065 0.2794)
			(end -0.12065 0.3048)
			(stroke
				(width 0.1)
				(type default)
			)
			(layer "F.Fab")
		)
		(fp_line
			(start 0.120396 0.2794)
			(end -0.12065 0.2794)
			(stroke
				(width 0.1)
				(type default)
			)
			(layer "F.Fab")
		)
		(fp_line
			(start -0.12065 -0.2794)
			(end 0.12065 -0.2794)
			(stroke
				(width 0.1)
				(type default)
			)
			(layer "F.Fab")
		)
		(fp_line
			(start 0.12065 -0.2794)
			(end 0.12065 -0.3048)
			(stroke
				(width 0.1)
				(type default)
			)
			(layer "F.Fab")
		)
		(fp_line
			(start 0.12065 -0.3048)
			(end 0.67945 -0.3048)
			(stroke
				(width 0.1)
				(type default)
			)
			(layer "F.Fab")
		)
		(fp_line
			(start 0.67945 -0.3048)
			(end 0.67945 0.3048)
			(stroke
				(width 0.1)
				(type default)
			)
			(layer "F.Fab")
		)
		(fp_line
			(start -0.67945 -0.305054)
			(end -0.12065 -0.305054)
			(stroke
				(width 0.1)
				(type default)
			)
			(layer "F.Fab")
		)
		(fp_line
			(start -0.12065 -0.305054)
			(end -0.12065 -0.2794)
			(stroke
				(width 0.1)
				(type default)
			)
			(layer "F.Fab")
		)
		(pad "1" smd circle
			(at -0.40005 0 270)
			(size 0 0)
			(layers "F.Cu" "F.Mask" "F.Paste")
			(net "RST_MB_PERST_2_ISO_N")
		)
		(pad "2" smd circle
			(at 0.40005 0 270)
			(size 0 0)
			(layers "F.Cu" "F.Mask" "F.Paste")
			(net "RST_MB_PERST_2_ISO_R_N")
		)
	)
	(footprint ""
		(layer "F.Cu")
		(at 359.85831 -261.814564 180)
		(property "Reference" "C836"
			(at 0 0 180)
			(layer "F.SilkS")
			(hide yes)
			(effects
				(font
					(size 1.27 1.27)
				)
			)
		)
		(property "Value" ""
			(at 0 0 180)
			(layer "F.Fab")
			(effects
				(font
					(size 1.27 1.27)
				)
			)
		)
		(duplicate_pad_numbers_are_jumpers no)
		(fp_line
			(start 0.7874 0.4064)
			(end -0.7874 0.4064)
			(stroke
				(width 0.1524)
				(type default)
			)
			(layer "F.SilkS")
		)
		(fp_line
			(start 0.7874 -0.4064)
			(end 0.7874 0.4064)
			(stroke
				(width 0.1524)
				(type default)
			)
			(layer "F.SilkS")
		)
		(fp_line
			(start -0.7874 0.4064)
			(end -0.7874 -0.4064)
			(stroke
				(width 0.1524)
				(type default)
			)
			(layer "F.SilkS")
		)
		(fp_line
			(start -0.7874 -0.4064)
			(end 0.7874 -0.4064)
			(stroke
				(width 0.1524)
				(type default)
			)
			(layer "F.SilkS")
		)
		(fp_line
			(start 0.67945 0.3048)
			(end 0.120396 0.3048)
			(stroke
				(width 0.1)
				(type default)
			)
			(layer "F.Fab")
		)
		(fp_line
			(start 0.67945 -0.3048)
			(end 0.67945 0.3048)
			(stroke
				(width 0.1)
				(type default)
			)
			(layer "F.Fab")
		)
		(fp_line
			(start 0.12065 -0.2794)
			(end 0.12065 -0.3048)
			(stroke
				(width 0.1)
				(type default)
			)
			(layer "F.Fab")
		)
		(fp_line
			(start 0.12065 -0.3048)
			(end 0.67945 -0.3048)
			(stroke
				(width 0.1)
				(type default)
			)
			(layer "F.Fab")
		)
		(fp_line
			(start 0.120396 0.3048)
			(end 0.120396 0.2794)
			(stroke
				(width 0.1)
				(type default)
			)
			(layer "F.Fab")
		)
		(fp_line
			(start 0.120396 0.2794)
			(end -0.12065 0.2794)
			(stroke
				(width 0.1)
				(type default)
			)
			(layer "F.Fab")
		)
		(fp_line
			(start -0.12065 0.3048)
			(end -0.67945 0.3048)
			(stroke
				(width 0.1)
				(type default)
			)
			(layer "F.Fab")
		)
		(fp_line
			(start -0.12065 0.2794)
			(end -0.12065 0.3048)
			(stroke
				(width 0.1)
				(type default)
			)
			(layer "F.Fab")
		)
		(fp_line
			(start -0.12065 -0.2794)
			(end 0.12065 -0.2794)
			(stroke
				(width 0.1)
				(type default)
			)
			(layer "F.Fab")
		)
		(fp_line
			(start -0.12065 -0.305054)
			(end -0.12065 -0.2794)
			(stroke
				(width 0.1)
				(type default)
			)
			(layer "F.Fab")
		)
		(fp_line
			(start -0.67945 0.3048)
			(end -0.67945 -0.305054)
			(stroke
				(width 0.1)
				(type default)
			)
			(layer "F.Fab")
		)
		(fp_line
			(start -0.67945 -0.305054)
			(end -0.12065 -0.305054)
			(stroke
				(width 0.1)
				(type default)
			)
			(layer "F.Fab")
		)
		(pad "1" smd circle
			(at -0.40005 0 180)
			(size 0 0)
			(layers "F.Cu" "F.Mask" "F.Paste")
			(net "GND")
		)
		(pad "2" smd circle
			(at 0.40005 0 180)
			(size 0 0)
			(layers "F.Cu" "F.Mask" "F.Paste")
			(net "FM_P0V8_PEX3_EN_R")
		)
	)
	(footprint ""
		(layer "F.Cu")
		(at 13.434822 -133.088126 180)
		(property "Reference" "PC353"
			(at 0 0 180)
			(layer "F.SilkS")
			(hide yes)
			(effects
				(font
					(size 1.27 1.27)
				)
			)
		)
		(property "Value" ""
			(at 0 0 180)
			(layer "F.Fab")
			(effects
				(font
					(size 1.27 1.27)
				)
			)
		)
		(duplicate_pad_numbers_are_jumpers no)
		(fp_line
			(start 1.524 0.762)
			(end -1.524 0.762)
			(stroke
				(width 0.1524)
				(type default)
			)
			(layer "F.SilkS")
		)
		(fp_line
			(start 1.524 -0.762)
			(end 1.524 0.762)
			(stroke
				(width 0.1524)
				(type default)
			)
			(layer "F.SilkS")
		)
		(fp_line
			(start -1.524 0.762)
			(end -1.524 -0.762)
			(stroke
				(width 0.1524)
				(type default)
			)
			(layer "F.SilkS")
		)
		(fp_line
			(start -1.524 -0.762)
			(end 1.524 -0.762)
			(stroke
				(width 0.1524)
				(type default)
			)
			(layer "F.SilkS")
		)
		(fp_line
			(start 1.1049 0.724916)
			(end 1.1049 -0.724916)
			(stroke
				(width 0.1)
				(type default)
			)
			(layer "F.Fab")
		)
		(fp_line
			(start 1.1049 -0.724916)
			(end -1.1049 -0.724916)
			(stroke
				(width 0.1)
				(type default)
			)
			(layer "F.Fab")
		)
		(fp_line
			(start -1.1049 0.724916)
			(end 1.1049 0.724916)
			(stroke
				(width 0.1)
				(type default)
			)
			(layer "F.Fab")
		)
		(fp_line
			(start -1.1049 -0.724916)
			(end -1.1049 0.724916)
			(stroke
				(width 0.1)
				(type default)
			)
			(layer "F.Fab")
		)
		(pad "1" smd rect
			(at -0.889 0)
			(size 1.016 1.27)
			(layers "F.Cu" "F.Mask" "F.Paste")
			(net "GND")
		)
		(pad "2" smd rect
			(at 0.889 0)
			(size 1.016 1.27)
			(layers "F.Cu" "F.Mask" "F.Paste")
			(net "P12V_AUX")
		)
	)
	(footprint ""
		(layer "F.Cu")
		(at 290.06673 -52.543456 180)
		(property "Reference" "PC572"
			(at 0 0 180)
			(layer "F.SilkS")
			(hide yes)
			(effects
				(font
					(size 1.27 1.27)
				)
			)
		)
		(property "Value" ""
			(at 0 0 180)
			(layer "F.Fab")
			(effects
				(font
					(size 1.27 1.27)
				)
			)
		)
		(duplicate_pad_numbers_are_jumpers no)
		(fp_line
			(start 0.7874 0.4064)
			(end -0.7874 0.4064)
			(stroke
				(width 0.1524)
				(type default)
			)
			(layer "F.SilkS")
		)
		(fp_line
			(start 0.7874 -0.4064)
			(end 0.7874 0.4064)
			(stroke
				(width 0.1524)
				(type default)
			)
			(layer "F.SilkS")
		)
		(fp_line
			(start -0.7874 0.4064)
			(end -0.7874 -0.4064)
			(stroke
				(width 0.1524)
				(type default)
			)
			(layer "F.SilkS")
		)
		(fp_line
			(start -0.7874 -0.4064)
			(end 0.7874 -0.4064)
			(stroke
				(width 0.1524)
				(type default)
			)
			(layer "F.SilkS")
		)
		(fp_line
			(start 0.67945 0.3048)
			(end 0.120396 0.3048)
			(stroke
				(width 0.1)
				(type default)
			)
			(layer "F.Fab")
		)
		(fp_line
			(start 0.67945 -0.3048)
			(end 0.67945 0.3048)
			(stroke
				(width 0.1)
				(type default)
			)
			(layer "F.Fab")
		)
		(fp_line
			(start 0.12065 -0.2794)
			(end 0.12065 -0.3048)
			(stroke
				(width 0.1)
				(type default)
			)
			(layer "F.Fab")
		)
		(fp_line
			(start 0.12065 -0.3048)
			(end 0.67945 -0.3048)
			(stroke
				(width 0.1)
				(type default)
			)
			(layer "F.Fab")
		)
		(fp_line
			(start 0.120396 0.3048)
			(end 0.120396 0.2794)
			(stroke
				(width 0.1)
				(type default)
			)
			(layer "F.Fab")
		)
		(fp_line
			(start 0.120396 0.2794)
			(end -0.12065 0.2794)
			(stroke
				(width 0.1)
				(type default)
			)
			(layer "F.Fab")
		)
		(fp_line
			(start -0.12065 0.3048)
			(end -0.67945 0.3048)
			(stroke
				(width 0.1)
				(type default)
			)
			(layer "F.Fab")
		)
		(fp_line
			(start -0.12065 0.2794)
			(end -0.12065 0.3048)
			(stroke
				(width 0.1)
				(type default)
			)
			(layer "F.Fab")
		)
		(fp_line
			(start -0.12065 -0.2794)
			(end 0.12065 -0.2794)
			(stroke
				(width 0.1)
				(type default)
			)
			(layer "F.Fab")
		)
		(fp_line
			(start -0.12065 -0.305054)
			(end -0.12065 -0.2794)
			(stroke
				(width 0.1)
				(type default)
			)
			(layer "F.Fab")
		)
		(fp_line
			(start -0.67945 0.3048)
			(end -0.67945 -0.305054)
			(stroke
				(width 0.1)
				(type default)
			)
			(layer "F.Fab")
		)
		(fp_line
			(start -0.67945 -0.305054)
			(end -0.12065 -0.305054)
			(stroke
				(width 0.1)
				(type default)
			)
			(layer "F.Fab")
		)
		(pad "1" smd circle
			(at -0.40005 0 180)
			(size 0 0)
			(layers "F.Cu" "F.Mask" "F.Paste")
			(net "P3V3_SSD10")
		)
		(pad "2" smd circle
			(at 0.40005 0 180)
			(size 0 0)
			(layers "F.Cu" "F.Mask" "F.Paste")
			(net "GND")
		)
	)
)
